# S9S_MB_2U (Grand Teton) — schematic netlist excerpt (pin names and nets, part order shuffled) for the footprints in the layout excerpt that follows; sources: Cadence DE-HDL packaged netlist, KiCad conversion of 03242023_DA0F0TMBIJ0_F0T_Motherboard_J_brd_V01_OCP.brd

PC1350  Q_CAP  0.1UF 25V 10% X7R  pkg 0402  page 271 : A = GND ; B = PVCCIN_CPU0_VREF
C828  Q_CAP_DIFFBUS  DIFF BUS_0.22UF 6.3V 20% X6S  pkg C0201  page 175 : \1\ = P5E_CPU1_PE1_TX_C_DN<4> ; \2\ = P5E_CPU1_PE1_TX_DN<4>

(kicad_pcb
	(version 20260206)
	(generator "pcbnew")
	(generator_version "10.0")
	(general
		(thickness 1.6)
		(legacy_teardrops no)
	)
	(paper "A4")
	(title_block
		(title "03242023_DA0F0TMBIJ0_F0T_Motherboard_J_brd_V01_OCP.brd")
		(comment 1 "Grand Teton / footprints 3131-3132 of 6105")
	)
	(layers
		(0 "F.Cu" signal "TOP")
		(4 "In1.Cu" signal "GND")
		(6 "In2.Cu" signal "IN1")
		(8 "In3.Cu" signal "GND1")
		(10 "In4.Cu" signal "IN2")
		(12 "In5.Cu" signal "GND2")
		(14 "In6.Cu" signal "IN3")
		(16 "In7.Cu" signal "GND3")
		(18 "In8.Cu" signal "VCC")
		(20 "In9.Cu" signal "VCC1")
		(22 "In10.Cu" signal "GND4")
		(24 "In11.Cu" signal "IN4")
		(26 "In12.Cu" signal "GND5")
		(28 "In13.Cu" signal "IN5")
		(30 "In14.Cu" signal "GND6")
		(32 "In15.Cu" signal "IN6")
		(34 "In16.Cu" signal "GND7")
		(2 "B.Cu" signal "BOTTOM")
		(9 "F.Adhes" user "F.Adhesive")
		(11 "B.Adhes" user "B.Adhesive")
		(13 "F.Paste" user "Package Geometry/Pastemask Top")
		(15 "B.Paste" user "Package Geometry/Pastemask Bottom")
		(5 "F.SilkS" user "Ref Des/Silkscreen Top")
		(7 "B.SilkS" user "Ref Des/Silkscreen Bottom")
		(1 "F.Mask" user "Board Geometry/Soldermask Top")
		(3 "B.Mask" user "Board Geometry/Soldermask Bottom")
		(17 "Dwgs.User" user "User.Drawings")
		(19 "Cmts.User" user "User.Comments")
		(21 "Eco1.User" user "User.Eco1")
		(23 "Eco2.User" user "User.Eco2")
		(25 "Edge.Cuts" user "Board Geometry/Outline")
		(27 "Margin" user)
		(31 "F.CrtYd" user "Package Geometry/Place Bound Top")
		(29 "B.CrtYd" user "Package Geometry/Place Bound Bottom")
		(35 "F.Fab" user "Ref Des/Assembly Top")
		(33 "B.Fab" user "Ref Des/Assembly Bottom")
	)
	(footprint ""
		(layer "F.Cu")
		(at 295.72204 -367.357152 -90)
		(property "Reference" "PC1350"
			(at 0 0 270)
			(layer "F.SilkS")
			(hide yes)
			(effects
				(font
					(size 1.27 1.27)
				)
			)
		)
		(property "Value" ""
			(at 0 0 270)
			(layer "F.Fab")
			(effects
				(font
					(size 1.27 1.27)
				)
			)
		)
		(duplicate_pad_numbers_are_jumpers no)
		(fp_line
			(start -0.7874 0.4064)
			(end -0.7874 -0.4064)
			(stroke
				(width 0.1524)
				(type default)
			)
			(layer "F.SilkS")
		)
		(fp_line
			(start 0.7874 0.4064)
			(end -0.7874 0.4064)
			(stroke
				(width 0.1524)
				(type default)
			)
			(layer "F.SilkS")
		)
		(fp_line
			(start -0.7874 -0.4064)
			(end 0.7874 -0.4064)
			(stroke
				(width 0.1524)
				(type default)
			)
			(layer "F.SilkS")
		)
		(fp_line
			(start 0.7874 -0.4064)
			(end 0.7874 0.4064)
			(stroke
				(width 0.1524)
				(type default)
			)
			(layer "F.SilkS")
		)
		(fp_line
			(start -0.67945 0.3048)
			(end -0.67945 -0.305054)
			(stroke
				(width 0.1)
				(type default)
			)
			(layer "F.Fab")
		)
		(fp_line
			(start -0.12065 0.3048)
			(end -0.67945 0.3048)
			(stroke
				(width 0.1)
				(type default)
			)
			(layer "F.Fab")
		)
		(fp_line
			(start 0.120396 0.3048)
			(end 0.120396 0.2794)
			(stroke
				(width 0.1)
				(type default)
			)
			(layer "F.Fab")
		)
		(fp_line
			(start 0.67945 0.3048)
			(end 0.120396 0.3048)
			(stroke
				(width 0.1)
				(type default)
			)
			(layer "F.Fab")
		)
		(fp_line
			(start -0.12065 0.2794)
			(end -0.12065 0.3048)
			(stroke
				(width 0.1)
				(type default)
			)
			(layer "F.Fab")
		)
		(fp_line
			(start 0.120396 0.2794)
			(end -0.12065 0.2794)
			(stroke
				(width 0.1)
				(type default)
			)
			(layer "F.Fab")
		)
		(fp_line
			(start -0.12065 -0.2794)
			(end 0.12065 -0.2794)
			(stroke
				(width 0.1)
				(type default)
			)
			(layer "F.Fab")
		)
		(fp_line
			(start 0.12065 -0.2794)
			(end 0.12065 -0.3048)
			(stroke
				(width 0.1)
				(type default)
			)
			(layer "F.Fab")
		)
		(fp_line
			(start 0.12065 -0.3048)
			(end 0.67945 -0.3048)
			(stroke
				(width 0.1)
				(type default)
			)
			(layer "F.Fab")
		)
		(fp_line
			(start 0.67945 -0.3048)
			(end 0.67945 0.3048)
			(stroke
				(width 0.1)
				(type default)
			)
			(layer "F.Fab")
		)
		(fp_line
			(start -0.67945 -0.305054)
			(end -0.12065 -0.305054)
			(stroke
				(width 0.1)
				(type default)
			)
			(layer "F.Fab")
		)
		(fp_line
			(start -0.12065 -0.305054)
			(end -0.12065 -0.2794)
			(stroke
				(width 0.1)
				(type default)
			)
			(layer "F.Fab")
		)
		(pad "1" smd circle
			(at -0.40005 0 270)
			(size 0 0)
			(layers "F.Cu" "F.Mask" "F.Paste")
			(net "GND")
		)
		(pad "2" smd circle
			(at 0.40005 0 270)
			(size 0 0)
			(layers "F.Cu" "F.Mask" "F.Paste")
			(net "PVCCIN_CPU0_VREF")
		)
	)
	(footprint ""
		(layer "F.Cu")
		(at 46.548294 -17.623536 90)
		(property "Reference" "C828"
			(at 0 0 90)
			(layer "F.SilkS")
			(hide yes)
			(effects
				(font
					(size 1.27 1.27)
				)
			)
		)
		(property "Value" ""
			(at 0 0 90)
			(layer "F.Fab")
			(effects
				(font
					(size 1.27 1.27)
				)
			)
		)
		(duplicate_pad_numbers_are_jumpers no)
		(fp_line
			(start 0.299974 -0.150114)
			(end 0.299974 0.150114)
			(stroke
				(width 0.1)
				(type default)
			)
			(layer "F.Fab")
		)
		(fp_line
			(start -0.299974 -0.150114)
			(end 0.299974 -0.150114)
			(stroke
				(width 0.1)
				(type default)
			)
			(layer "F.Fab")
		)
		(fp_line
			(start 0.299974 0.150114)
			(end -0.299974 0.150114)
			(stroke
				(width 0.1)
				(type default)
			)
			(layer "F.Fab")
		)
		(fp_line
			(start -0.299974 0.150114)
			(end -0.299974 -0.150114)
			(stroke
				(width 0.1)
				(type default)
			)
			(layer "F.Fab")
		)
		(pad "1" smd rect
			(at -0.2667 0 90)
			(size 0.3048 0.381)
			(layers "F.Cu" "F.Mask" "F.Paste")
			(net "P5E_CPU1_PE1_TX_C_DN<4>")
		)
		(pad "2" smd rect
			(at 0.2667 0 90)
			(size 0.3048 0.381)
			(layers "F.Cu" "F.Mask" "F.Paste")
			(net "P5E_CPU1_PE1_TX_DN<4>")
		)
	)
)
